(kicad_pcb
	(version 20241229)
	(generator "pcbnew")
	(generator_version "9.0")
	(general
		(thickness 1.61)
		(legacy_teardrops no)
	)
	(paper "A3")
	(title_block
		(title "RDIMM DDR5 Tester")
		(date "2026-05-21")
		(rev "2.2.0")
		(company "Antmicro")
		(comment 9 "footprints 603-607 of 796")
	)
	(layers
		(0 "F.Cu" signal)
		(4 "In1.Cu" power)
		(6 "In2.Cu" mixed)
		(8 "In3.Cu" power)
		(10 "In4.Cu" mixed)
		(12 "In5.Cu" power)
		(14 "In6.Cu" mixed)
		(16 "In7.Cu" power)
		(18 "In8.Cu" power)
		(20 "In9.Cu" mixed)
		(22 "In10.Cu" power)
		(2 "B.Cu" signal)
		(9 "F.Adhes" user "F.Adhesive")
		(11 "B.Adhes" user "B.Adhesive")
		(13 "F.Paste" user)
		(15 "B.Paste" user)
		(5 "F.SilkS" user "F.Silkscreen")
		(7 "B.SilkS" user "B.Silkscreen")
		(1 "F.Mask" user)
		(3 "B.Mask" user)
		(17 "Dwgs.User" user "User.Drawings")
		(19 "Cmts.User" user "User.Comments")
		(21 "Eco1.User" user "User.Eco1")
		(23 "Eco2.User" user "User.Eco2")
		(25 "Edge.Cuts" user)
		(27 "Margin" user)
		(31 "F.CrtYd" user "F.Courtyard")
		(29 "B.CrtYd" user "B.Courtyard")
		(35 "F.Fab" user)
		(33 "B.Fab" user)
	)
	(footprint "antmicro-footprints:R_0402_1005Metric"
		(layer "B.Cu")
		(at 211.91 151.875)
		(descr "Resistor SMD 0402")
		(tags "resistor SMD 0402")
		(property "Reference" "R10"
			(at 0.99 0.485 0)
			(layer "B.SilkS")
			(effects
				(font
					(size 0.7 0.7)
					(thickness 0.15)
				)
				(justify right bottom mirror)
			)
		)
		(property "Value" "R_100R_0402"
			(at -1.011843 -1.772047 0)
			(layer "B.Fab")
			(effects
				(font
					(size 0.7 0.7)
					(thickness 0.15)
				)
				(justify right bottom mirror)
			)
		)
		(property "Datasheet" "https://www.bourns.com/docs/product-datasheets/cr.pdf"
			(at 0 0 0)
			(layer "F.Fab")
			(hide yes)
			(effects
				(font
					(size 1.27 1.27)
					(thickness 0.15)
				)
			)
		)
		(property "Manufacturer" "Bourns"
			(at 0 0 0)
			(unlocked yes)
			(layer "B.Fab")
			(hide yes)
			(effects
				(font
					(size 1 1)
					(thickness 0.15)
				)
				(justify mirror)
			)
		)
		(property "MPN" "CR0402-FX-1000GLF"
			(at 0 0 0)
			(unlocked yes)
			(layer "B.Fab")
			(hide yes)
			(effects
				(font
					(size 1 1)
					(thickness 0.15)
				)
				(justify mirror)
			)
		)
		(property "Val" "100R"
			(at 0 0 0)
			(unlocked yes)
			(layer "B.Fab")
			(hide yes)
			(effects
				(font
					(size 1 1)
					(thickness 0.15)
				)
				(justify mirror)
			)
		)
		(property "License" "Apache-2.0"
			(at 0 0 0)
			(unlocked yes)
			(layer "B.Fab")
			(hide yes)
			(effects
				(font
					(size 1 1)
					(thickness 0.15)
				)
				(justify mirror)
			)
		)
		(property "Author" "Antmicro"
			(at 0 0 0)
			(unlocked yes)
			(layer "B.Fab")
			(hide yes)
			(effects
				(font
					(size 1 1)
					(thickness 0.15)
				)
				(justify mirror)
			)
		)
		(property "Tolerance" "1%"
			(at 0 0 0)
			(unlocked yes)
			(layer "B.Fab")
			(hide yes)
			(effects
				(font
					(size 1 1)
					(thickness 0.15)
				)
				(justify mirror)
			)
		)
		(sheetname "/HyperRAM + QSPI Flash/")
		(sheetfile "hyperram-flash.kicad_sch")
		(attr smd exclude_from_bom dnp)
		(fp_rect
			(start -0.925 0.47)
			(end 0.925 -0.47)
			(stroke
				(width 0.05)
				(type default)
			)
			(fill no)
			(layer "B.CrtYd")
		)
		(fp_rect
			(start -0.5 0.25)
			(end 0.5 -0.25)
			(stroke
				(width 0.15)
				(type solid)
			)
			(fill no)
			(layer "B.Fab")
		)
		(fp_text user "Author: Antmicro"
			(at -0.95 -4.169 180)
			(layer "B.Fab")
			(effects
				(font
					(size 0.7 0.7)
					(thickness 0.15)
				)
				(justify left bottom mirror)
			)
		)
		(fp_text user "${REFERENCE}"
			(at -0.95 -3.168 180)
			(layer "B.Fab")
			(effects
				(font
					(size 0.7 0.7)
					(thickness 0.15)
				)
				(justify left bottom mirror)
			)
		)
		(fp_text user "License: Apache-2.0"
			(at -0.95 -5.169 180)
			(layer "B.Fab")
			(effects
				(font
					(size 0.7 0.7)
					(thickness 0.15)
				)
				(justify left bottom mirror)
			)
		)
		(pad "1" smd roundrect
			(at -0.48 0)
			(size 0.59 0.64)
			(layers "B.Cu" "B.Mask" "B.Paste")
			(roundrect_rratio 0.25)
			(net 355 "/FPGA Config/FLASH.SCK")
			(pintype "passive")
		)
		(pad "2" smd roundrect
			(at 0.48 0)
			(size 0.59 0.64)
			(layers "B.Cu" "B.Mask" "B.Paste")
			(roundrect_rratio 0.25)
			(net 1 "GND")
			(pintype "passive")
		)
	)
	(footprint "antmicro-footprints:C_0603_1608Metric"
		(layer "B.Cu")
		(at 177.2 152.5 180)
		(descr "Capacitor SMD 0603")
		(tags "capacitor 0603")
		(property "Reference" "C73"
			(at -1.25 -1.925 0)
			(layer "B.SilkS")
			(effects
				(font
					(size 0.7 0.7)
					(thickness 0.15)
				)
				(justify left bottom mirror)
			)
		)
		(property "Value" "C_47u_0603"
			(at -1.42757 -1.770288 0)
			(layer "B.Fab")
			(effects
				(font
					(size 0.7 0.7)
					(thickness 0.15)
				)
				(justify left bottom mirror)
			)
		)
		(property "Datasheet" "https://www.murata.com/products/productdetail?partno=GRM188R60J476ME15%23"
			(at 0 0 180)
			(layer "F.Fab")
			(hide yes)
			(effects
				(font
					(size 1.27 1.27)
					(thickness 0.15)
				)
			)
		)
		(property "Manufacturer" "Murata"
			(at 0 0 180)
			(unlocked yes)
			(layer "B.Fab")
			(hide yes)
			(effects
				(font
					(size 1 1)
					(thickness 0.15)
				)
				(justify mirror)
			)
		)
		(property "MPN" "GRM188R60J476ME15D"
			(at 0 0 180)
			(unlocked yes)
			(layer "B.Fab")
			(hide yes)
			(effects
				(font
					(size 1 1)
					(thickness 0.15)
				)
				(justify mirror)
			)
		)
		(property "Val" "47u"
			(at 0 0 180)
			(unlocked yes)
			(layer "B.Fab")
			(hide yes)
			(effects
				(font
					(size 1 1)
					(thickness 0.15)
				)
				(justify mirror)
			)
		)
		(property "License" "Apache-2.0"
			(at 0 0 180)
			(unlocked yes)
			(layer "B.Fab")
			(hide yes)
			(effects
				(font
					(size 1 1)
					(thickness 0.15)
				)
				(justify mirror)
			)
		)
		(property "Author" "Antmicro"
			(at 0 0 180)
			(unlocked yes)
			(layer "B.Fab")
			(hide yes)
			(effects
				(font
					(size 1 1)
					(thickness 0.15)
				)
				(justify mirror)
			)
		)
		(property "Voltage" ""
			(at 0 0 180)
			(unlocked yes)
			(layer "B.Fab")
			(hide yes)
			(effects
				(font
					(size 1 1)
					(thickness 0.15)
				)
				(justify mirror)
			)
		)
		(property "Dielectric" ""
			(at 0 0 180)
			(unlocked yes)
			(layer "B.Fab")
			(hide yes)
			(effects
				(font
					(size 1 1)
					(thickness 0.15)
				)
				(justify mirror)
			)
		)
		(sheetname "/FPGA power/")
		(sheetfile "fpga-power.kicad_sch")
		(attr smd)
		(fp_line
			(start -0.15 0.4)
			(end 0.15 0.4)
			(stroke
				(width 0.15)
				(type solid)
			)
			(layer "B.SilkS")
		)
		(fp_line
			(start -0.15 -0.4)
			(end 0.15 -0.4)
			(stroke
				(width 0.15)
				(type solid)
			)
			(layer "B.SilkS")
		)
		(fp_rect
			(start -1.25 0.65)
			(end 1.25 -0.65)
			(stroke
				(width 0.05)
				(type solid)
			)
			(fill no)
			(layer "B.CrtYd")
		)
		(fp_rect
			(start -0.8 0.4)
			(end 0.8 -0.4)
			(stroke
				(width 0.15)
				(type solid)
			)
			(fill no)
			(layer "B.Fab")
		)
		(fp_text user "License: Apache-2.0"
			(at -1.682 -5.895 0)
			(layer "B.Fab")
			(effects
				(font
					(size 0.7 0.7)
					(thickness 0.15)
				)
				(justify left bottom mirror)
			)
		)
		(fp_text user "Author: Antmicro"
			(at -1.682 -4.894 0)
			(layer "B.Fab")
			(effects
				(font
					(size 0.7 0.7)
					(thickness 0.15)
				)
				(justify left bottom mirror)
			)
		)
		(fp_text user "${REFERENCE}"
			(at -1.682 -3.895 0)
			(layer "B.Fab")
			(effects
				(font
					(size 0.7 0.7)
					(thickness 0.15)
				)
				(justify left bottom mirror)
			)
		)
		(pad "1" smd roundrect
			(at -0.7 0 180)
			(size 0.8 1)
			(layers "B.Cu" "B.Mask" "B.Paste")
			(roundrect_rratio 0.2)
			(net 797 "+1V8")
			(pintype "passive")
		)
		(pad "2" smd roundrect
			(at 0.7 0 180)
			(size 0.8 1)
			(layers "B.Cu" "B.Mask" "B.Paste")
			(roundrect_rratio 0.2)
			(net 1 "GND")
			(pintype "passive")
		)
	)
	(footprint "antmicro-footprints:R_0402_1005Metric"
		(layer "B.Cu")
		(at 235.579999 132.805001 -90)
		(descr "Resistor SMD 0402")
		(tags "resistor SMD 0402")
		(property "Reference" "R125"
			(at -4.055001 -0.470001 90)
			(layer "B.SilkS")
			(effects
				(font
					(size 0.7 0.7)
					(thickness 0.15)
				)
				(justify left bottom mirror)
			)
		)
		(property "Value" "R_4k7_0402"
			(at -1.085 2.05 90)
			(layer "B.Fab")
			(effects
				(font
					(size 0.7 0.7)
					(thickness 0.15)
				)
				(justify left bottom mirror)
			)
		)
		(property "Datasheet" "https://www.bourns.com/docs/product-datasheets/cr.pdf"
			(at 0 0 270)
			(layer "F.Fab")
			(hide yes)
			(effects
				(font
					(size 1.27 1.27)
					(thickness 0.15)
				)
			)
		)
		(property "Manufacturer" "Bourns"
			(at 0 0 270)
			(unlocked yes)
			(layer "B.Fab")
			(hide yes)
			(effects
				(font
					(size 1 1)
					(thickness 0.15)
				)
				(justify mirror)
			)
		)
		(property "MPN" "CR0402-FX-4701GLF"
			(at 0 0 270)
			(unlocked yes)
			(layer "B.Fab")
			(hide yes)
			(effects
				(font
					(size 1 1)
					(thickness 0.15)
				)
				(justify mirror)
			)
		)
		(property "Val" "4k7"
			(at 0 0 270)
			(unlocked yes)
			(layer "B.Fab")
			(hide yes)
			(effects
				(font
					(size 1 1)
					(thickness 0.15)
				)
				(justify mirror)
			)
		)
		(property "License" "Apache-2.0"
			(at 0 0 270)
			(unlocked yes)
			(layer "B.Fab")
			(hide yes)
			(effects
				(font
					(size 1 1)
					(thickness 0.15)
				)
				(justify mirror)
			)
		)
		(property "Author" "Antmicro"
			(at 0 0 270)
			(unlocked yes)
			(layer "B.Fab")
			(hide yes)
			(effects
				(font
					(size 1 1)
					(thickness 0.15)
				)
				(justify mirror)
			)
		)
		(property "Tolerance" "1%"
			(at 0 0 270)
			(unlocked yes)
			(layer "B.Fab")
			(hide yes)
			(effects
				(font
					(size 1 1)
					(thickness 0.15)
				)
				(justify mirror)
			)
		)
		(sheetname "/I^{2}C + I3C/")
		(sheetfile "i2c.kicad_sch")
		(attr smd)
		(fp_rect
			(start -0.925 0.47)
			(end 0.925 -0.47)
			(stroke
				(width 0.05)
				(type default)
			)
			(fill no)
			(layer "B.CrtYd")
		)
		(fp_rect
			(start -0.5 0.25)
			(end 0.5 -0.25)
			(stroke
				(width 0.15)
				(type solid)
			)
			(fill no)
			(layer "B.Fab")
		)
		(fp_text user "${REFERENCE}"
			(at -0.95 -3.168 90)
			(layer "B.Fab")
			(effects
				(font
					(size 0.7 0.7)
					(thickness 0.15)
				)
				(justify left bottom mirror)
			)
		)
		(fp_text user "License: Apache-2.0"
			(at -0.95 -5.169 90)
			(layer "B.Fab")
			(effects
				(font
					(size 0.7 0.7)
					(thickness 0.15)
				)
				(justify left bottom mirror)
			)
		)
		(fp_text user "Author: Antmicro"
			(at -0.95 -4.169 90)
			(layer "B.Fab")
			(effects
				(font
					(size 0.7 0.7)
					(thickness 0.15)
				)
				(justify left bottom mirror)
			)
		)
		(pad "1" smd roundrect
			(at -0.48 0 270)
			(size 0.59 0.64)
			(layers "B.Cu" "B.Mask" "B.Paste")
			(roundrect_rratio 0.25)
			(net 201 "VDDSPD")
			(pintype "passive")
		)
		(pad "2" smd roundrect
			(at 0.48 0 270)
			(size 0.59 0.64)
			(layers "B.Cu" "B.Mask" "B.Paste")
			(roundrect_rratio 0.25)
			(net 460 "/DDR5 RDIMM/DDR.SCL")
			(pintype "passive")
		)
	)
	(footprint "antmicro-footprints:R_0402_1005Metric"
		(layer "B.Cu")
		(at 156.124499 191.299)
		(descr "Resistor SMD 0402")
		(tags "resistor SMD 0402")
		(property "Reference" "R191"
			(at -3.864499 0.441 0)
			(layer "B.SilkS")
			(effects
				(font
					(size 0.7 0.7)
					(thickness 0.15)
				)
				(justify right bottom mirror)
			)
		)
		(property "Value" "R_10k_0402"
			(at -1.011843 -1.772047 0)
			(layer "B.Fab")
			(effects
				(font
					(size 0.7 0.7)
					(thickness 0.15)
				)
				(justify right bottom mirror)
			)
		)
		(property "Datasheet" "https://www.bourns.com/docs/product-datasheets/cr.pdf"
			(at 0 0 0)
			(layer "F.Fab")
			(hide yes)
			(effects
				(font
					(size 1.27 1.27)
					(thickness 0.15)
				)
			)
		)
		(property "MPN" "CR0402-FX-1002GLF"
			(at 0 0 0)
			(unlocked yes)
			(layer "B.Fab")
			(hide yes)
			(effects
				(font
					(size 1 1)
					(thickness 0.15)
				)
				(justify mirror)
			)
		)
		(property "Manufacturer" "Bourns"
			(at 0 0 0)
			(unlocked yes)
			(layer "B.Fab")
			(hide yes)
			(effects
				(font
					(size 1 1)
					(thickness 0.15)
				)
				(justify mirror)
			)
		)
		(property "License" "Apache-2.0"
			(at 0 0 0)
			(unlocked yes)
			(layer "B.Fab")
			(hide yes)
			(effects
				(font
					(size 1 1)
					(thickness 0.15)
				)
				(justify mirror)
			)
		)
		(property "Author" "Antmicro"
			(at 0 0 0)
			(unlocked yes)
			(layer "B.Fab")
			(hide yes)
			(effects
				(font
					(size 1 1)
					(thickness 0.15)
				)
				(justify mirror)
			)
		)
		(property "Val" "10k"
			(at 0 0 0)
			(unlocked yes)
			(layer "B.Fab")
			(hide yes)
			(effects
				(font
					(size 1 1)
					(thickness 0.15)
				)
				(justify mirror)
			)
		)
		(property "Tolerance" "1%"
			(at 0 0 0)
			(unlocked yes)
			(layer "B.Fab")
			(hide yes)
			(effects
				(font
					(size 1 1)
					(thickness 0.15)
				)
				(justify mirror)
			)
		)
		(sheetname "/PCIe connector/")
		(sheetfile "pcie-connector.kicad_sch")
		(attr smd exclude_from_bom dnp)
		(fp_rect
			(start -0.925 0.47)
			(end 0.925 -0.47)
			(stroke
				(width 0.05)
				(type default)
			)
			(fill no)
			(layer "B.CrtYd")
		)
		(fp_rect
			(start -0.5 0.25)
			(end 0.5 -0.25)
			(stroke
				(width 0.15)
				(type solid)
			)
			(fill no)
			(layer "B.Fab")
		)
		(fp_text user "License: Apache-2.0"
			(at -0.95 -5.169 180)
			(layer "B.Fab")
			(effects
				(font
					(size 0.7 0.7)
					(thickness 0.15)
				)
				(justify left bottom mirror)
			)
		)
		(fp_text user "Author: Antmicro"
			(at -0.95 -4.169 180)
			(layer "B.Fab")
			(effects
				(font
					(size 0.7 0.7)
					(thickness 0.15)
				)
				(justify left bottom mirror)
			)
		)
		(fp_text user "${REFERENCE}"
			(at -0.95 -3.168 180)
			(layer "B.Fab")
			(effects
				(font
					(size 0.7 0.7)
					(thickness 0.15)
				)
				(justify left bottom mirror)
			)
		)
		(pad "1" smd roundrect
			(at -0.48 0)
			(size 0.59 0.64)
			(layers "B.Cu" "B.Mask" "B.Paste")
			(roundrect_rratio 0.25)
			(net 98 "PCIE.PWRGD")
			(pintype "passive")
		)
		(pad "2" smd roundrect
			(at 0.48 0)
			(size 0.59 0.64)
			(layers "B.Cu" "B.Mask" "B.Paste")
			(roundrect_rratio 0.25)
			(net 151 "+3V3")
			(pintype "passive")
		)
	)
	(footprint "antmicro-footprints:R_0402_1005Metric_EIA"
		(layer "B.Cu")
		(at 186 144.5 -90)
		(descr "Resistor SMD 0402 (1005 Metric), square (rectangular) end terminal, IPC_7351 nominal, (Body size source: IPC-SM-782 page 76, https://www.pcb-3d.com/wordpress/wp-content/uploads/ipc-sm-782a_amendment_1_and_2.pdf)")
		(tags "resistor 0402")
		(property "Reference" "R180"
			(at -1.94 -1.475 90)
			(layer "B.SilkS")
			(effects
				(font
					(size 0.7 0.7)
					(thickness 0.15)
				)
				(justify left bottom mirror)
			)
		)
		(property "Value" "R_240R_0402"
			(at 0 -1.169 90)
			(layer "B.Fab")
			(effects
				(font
					(size 0.7 0.7)
					(thickness 0.15)
				)
				(justify left bottom mirror)
			)
		)
		(property "Datasheet" "https://www.bourns.com/docs/product-datasheets/cr.pdf"
			(at 0 0 270)
			(layer "F.Fab")
			(hide yes)
			(effects
				(font
					(size 1.27 1.27)
					(thickness 0.15)
				)
			)
		)
		(property "MPN" "CR0402-FX-2400GLF"
			(at 0 0 270)
			(unlocked yes)
			(layer "B.Fab")
			(hide yes)
			(effects
				(font
					(size 1 1)
					(thickness 0.15)
				)
				(justify mirror)
			)
		)
		(property "Manufacturer" "Bourns"
			(at 0 0 270)
			(unlocked yes)
			(layer "B.Fab")
			(hide yes)
			(effects
				(font
					(size 1 1)
					(thickness 0.15)
				)
				(justify mirror)
			)
		)
		(property "License" "Apache-2.0"
			(at 0 0 270)
			(unlocked yes)
			(layer "B.Fab")
			(hide yes)
			(effects
				(font
					(size 1 1)
					(thickness 0.15)
				)
				(justify mirror)
			)
		)
		(property "Author" "Antmicro"
			(at 0 0 270)
			(unlocked yes)
			(layer "B.Fab")
			(hide yes)
			(effects
				(font
					(size 1 1)
					(thickness 0.15)
				)
				(justify mirror)
			)
		)
		(property "Val" "240R"
			(at 0 0 270)
			(unlocked yes)
			(layer "B.Fab")
			(hide yes)
			(effects
				(font
					(size 1 1)
					(thickness 0.15)
				)
				(justify mirror)
			)
		)
		(property "Tolerance" "1%"
			(at 0 0 270)
			(unlocked yes)
			(layer "B.Fab")
			(hide yes)
			(effects
				(font
					(size 1 1)
					(thickness 0.15)
				)
				(justify mirror)
			)
		)
		(sheetname "/FPGA banks HP/")
		(sheetfile "fpga-hp-banks.kicad_sch")
		(attr smd)
		(fp_rect
			(start -0.95 0.45)
			(end 0.95 -0.45)
			(stroke
				(width 0.05)
				(type default)
			)
			(fill no)
			(layer "B.CrtYd")
		)
		(fp_line
			(start -0.5 0.25)
			(end 0.499 0.25)
			(stroke
				(width 0.15)
				(type solid)
			)
			(layer "B.Fab")
		)
		(fp_line
			(start 0.499 0.25)
			(end 0.499 -0.249)
			(stroke
				(width 0.15)
				(type solid)
			)
			(layer "B.Fab")
		)
		(fp_line
			(start -0.5 -0.249)
			(end -0.5 0.25)
			(stroke
				(width 0.15)
				(type solid)
			)
			(layer "B.Fab")
		)
		(fp_line
			(start 0.499 -0.249)
			(end -0.5 -0.249)
			(stroke
				(width 0.15)
				(type solid)
			)
			(layer "B.Fab")
		)
		(fp_text user "License: Apache-2.0"
			(at -0.95 -4.369 90)
			(layer "B.Fab")
			(effects
				(font
					(size 0.7 0.7)
					(thickness 0.15)
				)
				(justify left bottom mirror)
			)
		)
		(fp_text user "Author: Antmicro"
			(at -0.95 -5.569 90)
			(layer "B.Fab")
			(effects
				(font
					(size 0.7 0.7)
					(thickness 0.15)
				)
				(justify left bottom mirror)
			)
		)
		(fp_text user "${REFERENCE}"
			(at -0.95 -3.169 90)
			(layer "B.Fab")
			(effects
				(font
					(size 0.7 0.7)
					(thickness 0.15)
				)
				(justify left bottom mirror)
			)
		)
		(pad "1" smd roundrect
			(at -0.5 0 180)
			(size 0.6 0.6)
			(layers "B.Cu" "B.Mask" "B.Paste")
			(roundrect_rratio 0.25)
			(net 600 "/FPGA banks HP/VRP_66")
			(pintype "passive")
		)
		(pad "2" smd roundrect
			(at 0.499 0 270)
			(size 0.6 0.6)
			(layers "B.Cu" "B.Mask" "B.Paste")
			(roundrect_rratio 0.25)
			(net 1 "GND")
			(pintype "passive")
		)
	)
)
